G04*
G04 #@! TF.GenerationSoftware,Altium Limited,Altium Designer,22.4.2 (48)*
G04*
G04 Layer_Color=16711935*
%FSLAX25Y25*%
%MOIN*%
G70*
G04*
G04 #@! TF.SameCoordinates,B69760C6-9901-4916-8BAC-4CFDAA04743E*
G04*
G04*
G04 #@! TF.FilePolarity,Negative*
G04*
G01*
G75*
%ADD59C,0.02800*%
%ADD60C,0.03200*%
G36*
X23143Y26843D02*
X24075Y26473D01*
X24920Y25934D01*
X25649Y25246D01*
X26236Y24433D01*
X26659Y23524D01*
X26904Y22552D01*
X26933Y22051D01*
X26933Y1165D01*
X4197D01*
X3909Y1165D01*
X3344Y1274D01*
X2810Y1488D01*
X2325Y1799D01*
X1909Y2196D01*
X1575Y2664D01*
X1335Y3188D01*
X1199Y3747D01*
X1185Y4034D01*
Y27031D01*
X21657D01*
X21657Y27031D01*
X21657Y27031D01*
X22159Y27031D01*
X23143Y26843D01*
D02*
G37*
G36*
X26933Y106224D02*
X26846Y105379D01*
X26367Y103749D01*
X25599Y102234D01*
X24567Y100884D01*
X23305Y99746D01*
X21858Y98857D01*
X20272Y98247D01*
X18601Y97937D01*
X17752Y97937D01*
X1185D01*
Y120807D01*
X1185Y121102D01*
X1301Y121681D01*
X1528Y122226D01*
X1856Y122717D01*
X2274Y123134D01*
X2765Y123462D01*
X3311Y123688D01*
X3890Y123803D01*
X4185Y123803D01*
X4185Y123803D01*
X26933D01*
X26933Y106224D01*
D02*
G37*
G36*
X263272Y3954D02*
X263248Y3672D01*
X263098Y3125D01*
X262849Y2615D01*
X262511Y2161D01*
X262094Y1777D01*
X261613Y1476D01*
X261085Y1270D01*
X260728Y1203D01*
X260244Y1165D01*
X233626Y1165D01*
X233626Y20437D01*
X233661Y21099D01*
X233978Y22385D01*
X234533Y23588D01*
X235304Y24665D01*
X236265Y25576D01*
X237381Y26291D01*
X238612Y26781D01*
X239912Y27031D01*
X240575D01*
X240575Y27031D01*
X263272D01*
X263272Y3954D01*
D02*
G37*
G36*
X260268Y123803D02*
X260268Y123803D01*
X260268D01*
X260728Y123769D01*
X261095Y123701D01*
X261616Y123500D01*
X262090Y123207D01*
X262504Y122831D01*
X262841Y122387D01*
X263091Y121888D01*
X263245Y121352D01*
X263272Y121074D01*
X263272Y97937D01*
X241059Y97937D01*
X240347D01*
X238948Y98207D01*
X237626Y98738D01*
X236429Y99510D01*
X235400Y100495D01*
X234577Y101657D01*
X233988Y102954D01*
X233657Y104340D01*
X233626Y105051D01*
X233626Y123803D01*
X260268D01*
X260268Y123803D01*
D02*
G37*
%LPC*%
G36*
X11825Y18523D02*
X10623D01*
X10525Y18504D01*
X10424D01*
X9245Y18269D01*
X9153Y18231D01*
X9054Y18211D01*
X7944Y17751D01*
X7860Y17696D01*
X7767Y17657D01*
X6768Y16989D01*
X6697Y16918D01*
X6613Y16862D01*
X5763Y16013D01*
X5708Y15929D01*
X5637Y15858D01*
X4969Y14859D01*
X4930Y14766D01*
X4875Y14682D01*
X4415Y13572D01*
X4395Y13473D01*
X4357Y13381D01*
X4122Y12201D01*
Y12101D01*
X4103Y12003D01*
Y10801D01*
X4122Y10702D01*
Y10602D01*
X4357Y9423D01*
X4395Y9330D01*
X4415Y9231D01*
X4875Y8121D01*
X4930Y8037D01*
X4969Y7945D01*
X5637Y6945D01*
X5708Y6874D01*
X5763Y6791D01*
X6613Y5941D01*
X6697Y5885D01*
X6768Y5814D01*
X7767Y5146D01*
X7860Y5108D01*
X7944Y5052D01*
X9054Y4592D01*
X9153Y4572D01*
X9245Y4534D01*
X10424Y4299D01*
X10525D01*
X10623Y4280D01*
X11825D01*
X11924Y4299D01*
X12024D01*
X13203Y4534D01*
X13296Y4572D01*
X13395Y4592D01*
X14505Y5052D01*
X14589Y5108D01*
X14681Y5146D01*
X15681Y5814D01*
X15752Y5885D01*
X15835Y5941D01*
X16685Y6791D01*
X16741Y6874D01*
X16812Y6945D01*
X17480Y7945D01*
X17518Y8037D01*
X17574Y8121D01*
X18034Y9231D01*
X18054Y9330D01*
X18092Y9423D01*
X18327Y10602D01*
Y10702D01*
X18346Y10801D01*
Y12003D01*
X18327Y12101D01*
Y12201D01*
X18092Y13381D01*
X18054Y13473D01*
X18034Y13572D01*
X17574Y14682D01*
X17518Y14766D01*
X17480Y14859D01*
X16812Y15858D01*
X16741Y15929D01*
X16685Y16013D01*
X15835Y16862D01*
X15752Y16918D01*
X15681Y16989D01*
X14681Y17657D01*
X14589Y17696D01*
X14505Y17751D01*
X13395Y18211D01*
X13296Y18231D01*
X13203Y18269D01*
X12024Y18504D01*
X11924D01*
X11825Y18523D01*
D02*
G37*
G36*
Y120886D02*
X10623D01*
X10525Y120866D01*
X10424D01*
X9245Y120632D01*
X9153Y120593D01*
X9054Y120574D01*
X7944Y120114D01*
X7860Y120058D01*
X7767Y120019D01*
X6768Y119351D01*
X6697Y119281D01*
X6613Y119225D01*
X5763Y118375D01*
X5708Y118291D01*
X5637Y118220D01*
X4969Y117221D01*
X4930Y117128D01*
X4875Y117044D01*
X4415Y115934D01*
X4395Y115835D01*
X4357Y115743D01*
X4122Y114564D01*
Y114463D01*
X4103Y114365D01*
Y113764D01*
Y113163D01*
X4122Y113064D01*
Y112964D01*
X4357Y111785D01*
X4395Y111692D01*
X4415Y111594D01*
X4875Y110483D01*
X4930Y110399D01*
X4969Y110307D01*
X5637Y109307D01*
X5708Y109236D01*
X5763Y109153D01*
X6613Y108303D01*
X6697Y108247D01*
X6768Y108176D01*
X7767Y107508D01*
X7860Y107470D01*
X7944Y107414D01*
X9054Y106954D01*
X9153Y106934D01*
X9245Y106896D01*
X10424Y106661D01*
X10525D01*
X10623Y106642D01*
X11825D01*
X11924Y106661D01*
X12024D01*
X13203Y106896D01*
X13296Y106934D01*
X13395Y106954D01*
X14505Y107414D01*
X14589Y107470D01*
X14681Y107508D01*
X15681Y108176D01*
X15752Y108247D01*
X15835Y108303D01*
X16685Y109153D01*
X16741Y109236D01*
X16812Y109307D01*
X17480Y110307D01*
X17518Y110399D01*
X17574Y110483D01*
X18034Y111594D01*
X18054Y111692D01*
X18092Y111785D01*
X18327Y112964D01*
Y113064D01*
X18346Y113163D01*
Y113764D01*
Y114365D01*
X18327Y114463D01*
Y114564D01*
X18092Y115743D01*
X18054Y115835D01*
X18034Y115934D01*
X17574Y117044D01*
X17518Y117128D01*
X17480Y117221D01*
X16812Y118220D01*
X16741Y118291D01*
X16685Y118375D01*
X15835Y119225D01*
X15752Y119281D01*
X15681Y119351D01*
X14681Y120019D01*
X14589Y120058D01*
X14505Y120114D01*
X13395Y120574D01*
X13296Y120593D01*
X13203Y120632D01*
X12024Y120866D01*
X11924D01*
X11825Y120886D01*
D02*
G37*
G36*
X250014Y18523D02*
X248812D01*
X248714Y18504D01*
X248613D01*
X247434Y18269D01*
X247342Y18231D01*
X247243Y18211D01*
X246133Y17751D01*
X246049Y17696D01*
X245956Y17657D01*
X244957Y16989D01*
X244886Y16918D01*
X244802Y16862D01*
X243952Y16013D01*
X243897Y15929D01*
X243826Y15858D01*
X243158Y14859D01*
X243119Y14766D01*
X243064Y14682D01*
X242604Y13572D01*
X242584Y13473D01*
X242546Y13381D01*
X242311Y12201D01*
Y12101D01*
X242291Y12003D01*
Y10801D01*
X242311Y10702D01*
Y10602D01*
X242546Y9423D01*
X242584Y9330D01*
X242604Y9231D01*
X243064Y8121D01*
X243119Y8037D01*
X243158Y7945D01*
X243826Y6945D01*
X243897Y6874D01*
X243952Y6791D01*
X244802Y5941D01*
X244886Y5885D01*
X244957Y5814D01*
X245956Y5146D01*
X246049Y5108D01*
X246133Y5052D01*
X247243Y4592D01*
X247342Y4572D01*
X247434Y4534D01*
X248613Y4299D01*
X248714D01*
X248812Y4280D01*
X250014D01*
X250113Y4299D01*
X250213D01*
X251392Y4534D01*
X251485Y4572D01*
X251584Y4592D01*
X252694Y5052D01*
X252778Y5108D01*
X252870Y5146D01*
X253870Y5814D01*
X253941Y5885D01*
X254024Y5941D01*
X254874Y6791D01*
X254930Y6874D01*
X255001Y6945D01*
X255669Y7945D01*
X255707Y8037D01*
X255763Y8121D01*
X256223Y9231D01*
X256243Y9330D01*
X256281Y9423D01*
X256516Y10602D01*
Y10702D01*
X256535Y10801D01*
Y12003D01*
X256516Y12101D01*
Y12201D01*
X256281Y13381D01*
X256243Y13473D01*
X256223Y13572D01*
X255763Y14682D01*
X255707Y14766D01*
X255669Y14859D01*
X255001Y15858D01*
X254930Y15929D01*
X254874Y16013D01*
X254024Y16862D01*
X253941Y16918D01*
X253870Y16989D01*
X252870Y17657D01*
X252778Y17696D01*
X252694Y17751D01*
X251584Y18211D01*
X251485Y18231D01*
X251392Y18269D01*
X250213Y18504D01*
X250113D01*
X250014Y18523D01*
D02*
G37*
G36*
Y120886D02*
X248812D01*
X248714Y120866D01*
X248613D01*
X247434Y120632D01*
X247342Y120593D01*
X247243Y120574D01*
X246133Y120114D01*
X246049Y120058D01*
X245956Y120019D01*
X244957Y119351D01*
X244886Y119281D01*
X244802Y119225D01*
X243952Y118375D01*
X243897Y118291D01*
X243826Y118220D01*
X243158Y117221D01*
X243119Y117128D01*
X243064Y117044D01*
X242604Y115934D01*
X242584Y115835D01*
X242546Y115743D01*
X242311Y114564D01*
Y114463D01*
X242291Y114365D01*
Y113163D01*
X242311Y113064D01*
Y112964D01*
X242546Y111785D01*
X242584Y111692D01*
X242604Y111594D01*
X243064Y110483D01*
X243119Y110399D01*
X243158Y110307D01*
X243826Y109307D01*
X243897Y109236D01*
X243952Y109153D01*
X244802Y108303D01*
X244886Y108247D01*
X244957Y108176D01*
X245956Y107508D01*
X246049Y107470D01*
X246133Y107414D01*
X247243Y106954D01*
X247342Y106934D01*
X247434Y106896D01*
X248613Y106661D01*
X248714D01*
X248812Y106642D01*
X250014D01*
X250113Y106661D01*
X250213D01*
X251392Y106896D01*
X251485Y106934D01*
X251584Y106954D01*
X252694Y107414D01*
X252778Y107470D01*
X252870Y107508D01*
X253870Y108176D01*
X253941Y108247D01*
X254024Y108303D01*
X254874Y109153D01*
X254930Y109236D01*
X255001Y109307D01*
X255669Y110307D01*
X255707Y110399D01*
X255763Y110483D01*
X256223Y111594D01*
X256243Y111692D01*
X256281Y111785D01*
X256516Y112964D01*
Y113064D01*
X256535Y113163D01*
Y114365D01*
X256516Y114463D01*
Y114564D01*
X256281Y115743D01*
X256243Y115835D01*
X256223Y115934D01*
X255763Y117044D01*
X255707Y117128D01*
X255669Y117221D01*
X255001Y118220D01*
X254930Y118291D01*
X254874Y118375D01*
X254024Y119225D01*
X253941Y119281D01*
X253870Y119351D01*
X252870Y120019D01*
X252778Y120058D01*
X252694Y120114D01*
X251584Y120574D01*
X251485Y120593D01*
X251392Y120632D01*
X250213Y120866D01*
X250113D01*
X250014Y120886D01*
D02*
G37*
%LPD*%
D59*
X215400Y47200D02*
D03*
X198300Y65800D02*
D03*
X187200Y65700D02*
D03*
X108600Y37300D02*
D03*
X116925D02*
D03*
X125250D02*
D03*
X133575D02*
D03*
X141900D02*
D03*
X108700Y29000D02*
D03*
X117025D02*
D03*
X125350D02*
D03*
X133675D02*
D03*
X142000D02*
D03*
X108700Y45700D02*
D03*
X117025D02*
D03*
X125350D02*
D03*
X133675D02*
D03*
X142000D02*
D03*
X108700Y54100D02*
D03*
X117025D02*
D03*
X125350D02*
D03*
X133675D02*
D03*
X142000D02*
D03*
X108600Y62100D02*
D03*
X116925D02*
D03*
X125250D02*
D03*
X133575D02*
D03*
X141900D02*
D03*
X108600Y70400D02*
D03*
X116925D02*
D03*
X125250D02*
D03*
X133575D02*
D03*
X141900D02*
D03*
Y78800D02*
D03*
X133575D02*
D03*
X125250D02*
D03*
X116925D02*
D03*
X108600D02*
D03*
X193900Y56000D02*
D03*
X225100Y61200D02*
D03*
X67900Y59000D02*
D03*
X56600Y49000D02*
D03*
X62800Y56700D02*
D03*
X65561Y53239D02*
D03*
X54800Y63300D02*
D03*
X69500Y66300D02*
D03*
X208600Y72100D02*
D03*
X137700Y104200D02*
D03*
Y111200D02*
D03*
X217400Y80000D02*
D03*
X121200Y102269D02*
D03*
Y106700D02*
D03*
X207517Y32817D02*
D03*
X217200Y72100D02*
D03*
X207517Y43428D02*
D03*
X222100Y40500D02*
D03*
D60*
X75800Y74400D02*
D03*
X87968Y80005D02*
D03*
X83568D02*
D03*
X79232Y80753D02*
D03*
X80035Y74573D02*
D03*
X84391Y75195D02*
D03*
X88791D02*
D03*
X18874Y81741D02*
D03*
X17342Y77617D02*
D03*
X19368Y73711D02*
D03*
X23616Y72562D02*
D03*
X27335Y74913D02*
D03*
X31689Y75547D02*
D03*
X36089D02*
D03*
X40202Y73983D02*
D03*
X47600Y75200D02*
D03*
X56960Y75547D02*
D03*
X61360D02*
D03*
X65760D02*
D03*
X70160D02*
D03*
X75868Y80753D02*
D03*
X71486Y80358D02*
D03*
X67086D02*
D03*
X62686D02*
D03*
X58286D02*
D03*
X53886D02*
D03*
X49486D02*
D03*
X45088Y80484D02*
D03*
X40689Y80358D02*
D03*
X36289D02*
D03*
X31889D02*
D03*
X27503Y80696D02*
D03*
X23955Y83298D02*
D03*
X259467Y120459D02*
D03*
Y110459D02*
D03*
Y100459D02*
D03*
Y90459D02*
D03*
Y80459D02*
D03*
Y70459D02*
D03*
Y60459D02*
D03*
Y50459D02*
D03*
Y40459D02*
D03*
Y30459D02*
D03*
Y20459D02*
D03*
Y10459D02*
D03*
X249467Y100459D02*
D03*
Y90459D02*
D03*
Y20459D02*
D03*
X239467Y120459D02*
D03*
Y110459D02*
D03*
Y100459D02*
D03*
Y90459D02*
D03*
Y60459D02*
D03*
Y50459D02*
D03*
Y20459D02*
D03*
Y10459D02*
D03*
X229467Y120459D02*
D03*
Y110459D02*
D03*
Y100459D02*
D03*
Y90459D02*
D03*
Y80459D02*
D03*
Y70459D02*
D03*
Y60459D02*
D03*
Y10459D02*
D03*
X219467Y120459D02*
D03*
Y110459D02*
D03*
Y100459D02*
D03*
Y90459D02*
D03*
X209467Y120459D02*
D03*
Y110459D02*
D03*
Y100459D02*
D03*
Y60459D02*
D03*
X199467Y120459D02*
D03*
Y110459D02*
D03*
Y80459D02*
D03*
Y30459D02*
D03*
X189467Y120459D02*
D03*
Y90459D02*
D03*
Y80459D02*
D03*
Y60459D02*
D03*
Y50459D02*
D03*
Y40459D02*
D03*
Y30459D02*
D03*
Y10459D02*
D03*
X179467Y120459D02*
D03*
Y90459D02*
D03*
Y60459D02*
D03*
Y50459D02*
D03*
Y40459D02*
D03*
Y20459D02*
D03*
X169467Y120459D02*
D03*
Y80459D02*
D03*
Y60459D02*
D03*
Y50459D02*
D03*
Y30459D02*
D03*
Y20459D02*
D03*
X159467Y120459D02*
D03*
Y90459D02*
D03*
Y80459D02*
D03*
Y70459D02*
D03*
Y40459D02*
D03*
Y30459D02*
D03*
Y20459D02*
D03*
X149467Y120459D02*
D03*
Y20459D02*
D03*
X139467Y120459D02*
D03*
Y20459D02*
D03*
X129467Y120459D02*
D03*
Y20459D02*
D03*
X119467Y120459D02*
D03*
Y110459D02*
D03*
Y20459D02*
D03*
X109467Y120459D02*
D03*
Y20459D02*
D03*
X99467Y120459D02*
D03*
Y110459D02*
D03*
Y20459D02*
D03*
X89467Y120459D02*
D03*
Y110459D02*
D03*
Y100459D02*
D03*
Y90459D02*
D03*
Y50459D02*
D03*
Y40459D02*
D03*
Y30459D02*
D03*
Y10459D02*
D03*
X79467Y120459D02*
D03*
Y110459D02*
D03*
Y100459D02*
D03*
Y90459D02*
D03*
Y20459D02*
D03*
Y10459D02*
D03*
X69467Y120459D02*
D03*
Y110459D02*
D03*
Y100459D02*
D03*
Y90459D02*
D03*
Y50459D02*
D03*
Y40459D02*
D03*
Y20459D02*
D03*
X59467Y120459D02*
D03*
Y110459D02*
D03*
Y100459D02*
D03*
Y90459D02*
D03*
Y10459D02*
D03*
X49467Y120459D02*
D03*
Y110459D02*
D03*
Y100459D02*
D03*
Y90459D02*
D03*
Y40459D02*
D03*
Y30459D02*
D03*
Y20459D02*
D03*
Y10459D02*
D03*
X39467Y120459D02*
D03*
Y110459D02*
D03*
Y100459D02*
D03*
Y90459D02*
D03*
Y70459D02*
D03*
Y60459D02*
D03*
Y50459D02*
D03*
Y40459D02*
D03*
Y30459D02*
D03*
Y20459D02*
D03*
Y10459D02*
D03*
X29467Y120459D02*
D03*
Y110459D02*
D03*
Y100459D02*
D03*
Y70459D02*
D03*
Y60459D02*
D03*
Y50459D02*
D03*
Y40459D02*
D03*
Y30459D02*
D03*
Y20459D02*
D03*
Y10459D02*
D03*
X19467Y120459D02*
D03*
Y110459D02*
D03*
Y100459D02*
D03*
Y60459D02*
D03*
Y50459D02*
D03*
Y40459D02*
D03*
Y30459D02*
D03*
Y20459D02*
D03*
X9467Y100459D02*
D03*
Y90459D02*
D03*
Y80459D02*
D03*
Y70459D02*
D03*
Y60459D02*
D03*
Y50459D02*
D03*
Y40459D02*
D03*
Y30459D02*
D03*
Y20459D02*
D03*
M02*
